(kicad_pcb
	(version 20260206)
	(generator "pcbnew")
	(generator_version "10.0")
	(general
		(thickness 1.6)
		(legacy_teardrops no)
	)
	(paper "A4")
	(title_block
		(title "01162023_DA0F0TEBIF0_F0T_Expander_BD_F_brd_V02_OCP.brd")
		(comment 1 "Grand Teton / footprints 124-130 of 9728")
	)
	(layers
		(0 "F.Cu" signal "TOP")
		(4 "In1.Cu" signal "GND")
		(6 "In2.Cu" signal "VCC")
		(8 "In3.Cu" signal "VCC1")
		(10 "In4.Cu" signal "GND1")
		(12 "In5.Cu" signal "IN1")
		(14 "In6.Cu" signal "GND2")
		(16 "In7.Cu" signal "IN2")
		(18 "In8.Cu" signal "GND3")
		(20 "In9.Cu" signal "IN3")
		(22 "In10.Cu" signal "GND4")
		(24 "In11.Cu" signal "IN4")
		(26 "In12.Cu" signal "GND5")
		(28 "In13.Cu" signal "IN5")
		(30 "In14.Cu" signal "GND6")
		(32 "In15.Cu" signal "IN6")
		(34 "In16.Cu" signal "GND7")
		(2 "B.Cu" signal "BOTTOM")
		(9 "F.Adhes" user "F.Adhesive")
		(11 "B.Adhes" user "B.Adhesive")
		(13 "F.Paste" user "Package Geometry/Pastemask Top")
		(15 "B.Paste" user "Package Geometry/Pastemask Bottom")
		(5 "F.SilkS" user "Ref Des/Silkscreen Top")
		(7 "B.SilkS" user "Ref Des/Silkscreen Bottom")
		(1 "F.Mask" user "Board Geometry/Soldermask Top")
		(3 "B.Mask" user "Board Geometry/Soldermask Bottom")
		(17 "Dwgs.User" user "User.Drawings")
		(19 "Cmts.User" user "User.Comments")
		(21 "Eco1.User" user "User.Eco1")
		(23 "Eco2.User" user "User.Eco2")
		(25 "Edge.Cuts" user "Board Geometry/Outline")
		(27 "Margin" user)
		(31 "F.CrtYd" user "Package Geometry/Place Bound Top")
		(29 "B.CrtYd" user "Package Geometry/Place Bound Bottom")
		(35 "F.Fab" user "Ref Des/Assembly Top")
		(33 "B.Fab" user "Ref Des/Assembly Bottom")
	)
	(footprint ""
		(layer "F.Cu")
		(at 13.220192 -394.130784 -90)
		(property "Reference" "R6745"
			(at 0 0 270)
			(layer "F.SilkS")
			(hide yes)
			(effects
				(font
					(size 1.27 1.27)
				)
			)
		)
		(property "Value" ""
			(at 0 0 270)
			(layer "F.Fab")
			(effects
				(font
					(size 1.27 1.27)
				)
			)
		)
		(duplicate_pad_numbers_are_jumpers no)
		(fp_line
			(start -0.7874 0.4064)
			(end -0.7874 -0.4064)
			(stroke
				(width 0.1524)
				(type default)
			)
			(layer "F.SilkS")
		)
		(fp_line
			(start 0.7874 0.4064)
			(end -0.7874 0.4064)
			(stroke
				(width 0.1524)
				(type default)
			)
			(layer "F.SilkS")
		)
		(fp_line
			(start -0.7874 -0.4064)
			(end 0.7874 -0.4064)
			(stroke
				(width 0.1524)
				(type default)
			)
			(layer "F.SilkS")
		)
		(fp_line
			(start 0.7874 -0.4064)
			(end 0.7874 0.4064)
			(stroke
				(width 0.1524)
				(type default)
			)
			(layer "F.SilkS")
		)
		(fp_line
			(start -0.67945 0.3048)
			(end -0.67945 -0.305054)
			(stroke
				(width 0.1)
				(type default)
			)
			(layer "F.Fab")
		)
		(fp_line
			(start -0.12065 0.3048)
			(end -0.67945 0.3048)
			(stroke
				(width 0.1)
				(type default)
			)
			(layer "F.Fab")
		)
		(fp_line
			(start 0.120396 0.3048)
			(end 0.120396 0.2794)
			(stroke
				(width 0.1)
				(type default)
			)
			(layer "F.Fab")
		)
		(fp_line
			(start 0.67945 0.3048)
			(end 0.120396 0.3048)
			(stroke
				(width 0.1)
				(type default)
			)
			(layer "F.Fab")
		)
		(fp_line
			(start -0.12065 0.2794)
			(end -0.12065 0.3048)
			(stroke
				(width 0.1)
				(type default)
			)
			(layer "F.Fab")
		)
		(fp_line
			(start 0.120396 0.2794)
			(end -0.12065 0.2794)
			(stroke
				(width 0.1)
				(type default)
			)
			(layer "F.Fab")
		)
		(fp_line
			(start -0.12065 -0.2794)
			(end 0.12065 -0.2794)
			(stroke
				(width 0.1)
				(type default)
			)
			(layer "F.Fab")
		)
		(fp_line
			(start 0.12065 -0.2794)
			(end 0.12065 -0.3048)
			(stroke
				(width 0.1)
				(type default)
			)
			(layer "F.Fab")
		)
		(fp_line
			(start 0.12065 -0.3048)
			(end 0.67945 -0.3048)
			(stroke
				(width 0.1)
				(type default)
			)
			(layer "F.Fab")
		)
		(fp_line
			(start 0.67945 -0.3048)
			(end 0.67945 0.3048)
			(stroke
				(width 0.1)
				(type default)
			)
			(layer "F.Fab")
		)
		(fp_line
			(start -0.67945 -0.305054)
			(end -0.12065 -0.305054)
			(stroke
				(width 0.1)
				(type default)
			)
			(layer "F.Fab")
		)
		(fp_line
			(start -0.12065 -0.305054)
			(end -0.12065 -0.2794)
			(stroke
				(width 0.1)
				(type default)
			)
			(layer "F.Fab")
		)
		(pad "1" smd circle
			(at -0.40005 0 270)
			(size 0 0)
			(layers "F.Cu" "F.Mask" "F.Paste")
			(net "GND")
		)
		(pad "2" smd circle
			(at 0.40005 0 270)
			(size 0 0)
			(layers "F.Cu" "F.Mask" "F.Paste")
			(net "BIC_USB_8042_HUB_GANGED")
		)
	)
	(footprint ""
		(layer "F.Cu")
		(at 60.437268 -393.16279 -90)
		(property "Reference" "C4010"
			(at 0 0 270)
			(layer "F.SilkS")
			(hide yes)
			(effects
				(font
					(size 1.27 1.27)
				)
			)
		)
		(property "Value" ""
			(at 0 0 270)
			(layer "F.Fab")
			(effects
				(font
					(size 1.27 1.27)
				)
			)
		)
		(duplicate_pad_numbers_are_jumpers no)
		(fp_line
			(start -0.7874 0.4064)
			(end -0.7874 -0.4064)
			(stroke
				(width 0.1524)
				(type default)
			)
			(layer "F.SilkS")
		)
		(fp_line
			(start 0.7874 0.4064)
			(end -0.7874 0.4064)
			(stroke
				(width 0.1524)
				(type default)
			)
			(layer "F.SilkS")
		)
		(fp_line
			(start -0.7874 -0.4064)
			(end 0.7874 -0.4064)
			(stroke
				(width 0.1524)
				(type default)
			)
			(layer "F.SilkS")
		)
		(fp_line
			(start 0.7874 -0.4064)
			(end 0.7874 0.4064)
			(stroke
				(width 0.1524)
				(type default)
			)
			(layer "F.SilkS")
		)
		(fp_line
			(start -0.67945 0.3048)
			(end -0.67945 -0.305054)
			(stroke
				(width 0.1)
				(type default)
			)
			(layer "F.Fab")
		)
		(fp_line
			(start -0.12065 0.3048)
			(end -0.67945 0.3048)
			(stroke
				(width 0.1)
				(type default)
			)
			(layer "F.Fab")
		)
		(fp_line
			(start 0.120396 0.3048)
			(end 0.120396 0.2794)
			(stroke
				(width 0.1)
				(type default)
			)
			(layer "F.Fab")
		)
		(fp_line
			(start 0.67945 0.3048)
			(end 0.120396 0.3048)
			(stroke
				(width 0.1)
				(type default)
			)
			(layer "F.Fab")
		)
		(fp_line
			(start -0.12065 0.2794)
			(end -0.12065 0.3048)
			(stroke
				(width 0.1)
				(type default)
			)
			(layer "F.Fab")
		)
		(fp_line
			(start 0.120396 0.2794)
			(end -0.12065 0.2794)
			(stroke
				(width 0.1)
				(type default)
			)
			(layer "F.Fab")
		)
		(fp_line
			(start -0.12065 -0.2794)
			(end 0.12065 -0.2794)
			(stroke
				(width 0.1)
				(type default)
			)
			(layer "F.Fab")
		)
		(fp_line
			(start 0.12065 -0.2794)
			(end 0.12065 -0.3048)
			(stroke
				(width 0.1)
				(type default)
			)
			(layer "F.Fab")
		)
		(fp_line
			(start 0.12065 -0.3048)
			(end 0.67945 -0.3048)
			(stroke
				(width 0.1)
				(type default)
			)
			(layer "F.Fab")
		)
		(fp_line
			(start 0.67945 -0.3048)
			(end 0.67945 0.3048)
			(stroke
				(width 0.1)
				(type default)
			)
			(layer "F.Fab")
		)
		(fp_line
			(start -0.67945 -0.305054)
			(end -0.12065 -0.305054)
			(stroke
				(width 0.1)
				(type default)
			)
			(layer "F.Fab")
		)
		(fp_line
			(start -0.12065 -0.305054)
			(end -0.12065 -0.2794)
			(stroke
				(width 0.1)
				(type default)
			)
			(layer "F.Fab")
		)
		(pad "1" smd circle
			(at -0.40005 0 270)
			(size 0 0)
			(layers "F.Cu" "F.Mask" "F.Paste")
			(net "GND")
		)
		(pad "2" smd circle
			(at 0.40005 0 270)
			(size 0 0)
			(layers "F.Cu" "F.Mask" "F.Paste")
			(net "GPU_HGX_DETECT_N")
		)
	)
	(footprint ""
		(layer "F.Cu")
		(at 431.032412 -356.244906 90)
		(property "Reference" "C2461"
			(at 0 0 90)
			(layer "F.SilkS")
			(hide yes)
			(effects
				(font
					(size 1.27 1.27)
				)
			)
		)
		(property "Value" ""
			(at 0 0 90)
			(layer "F.Fab")
			(effects
				(font
					(size 1.27 1.27)
				)
			)
		)
		(duplicate_pad_numbers_are_jumpers no)
		(fp_line
			(start 0.299974 -0.150114)
			(end 0.299974 0.150114)
			(stroke
				(width 0.1)
				(type default)
			)
			(layer "F.Fab")
		)
		(fp_line
			(start -0.299974 -0.150114)
			(end 0.299974 -0.150114)
			(stroke
				(width 0.1)
				(type default)
			)
			(layer "F.Fab")
		)
		(fp_line
			(start 0.299974 0.150114)
			(end -0.299974 0.150114)
			(stroke
				(width 0.1)
				(type default)
			)
			(layer "F.Fab")
		)
		(fp_line
			(start -0.299974 0.150114)
			(end -0.299974 -0.150114)
			(stroke
				(width 0.1)
				(type default)
			)
			(layer "F.Fab")
		)
		(pad "1" smd rect
			(at -0.2667 0 90)
			(size 0.3048 0.381)
			(layers "F.Cu" "F.Mask" "F.Paste")
			(net "P5E_PEX3_STN4_TX_DP<68>")
		)
		(pad "2" smd rect
			(at 0.2667 0 90)
			(size 0.3048 0.381)
			(layers "F.Cu" "F.Mask" "F.Paste")
			(net "P5E_PEX3_STN4_TX_C_DP<68>")
		)
	)
	(footprint ""
		(layer "F.Cu")
		(at 89.0016 -304.036476 90)
		(property "Reference" "R1247"
			(at 0 0 90)
			(layer "F.SilkS")
			(hide yes)
			(effects
				(font
					(size 1.27 1.27)
				)
			)
		)
		(property "Value" ""
			(at 0 0 90)
			(layer "F.Fab")
			(effects
				(font
					(size 1.27 1.27)
				)
			)
		)
		(duplicate_pad_numbers_are_jumpers no)
		(fp_line
			(start 0.7874 -0.4064)
			(end 0.7874 0.4064)
			(stroke
				(width 0.1524)
				(type default)
			)
			(layer "F.SilkS")
		)
		(fp_line
			(start -0.7874 -0.4064)
			(end 0.7874 -0.4064)
			(stroke
				(width 0.1524)
				(type default)
			)
			(layer "F.SilkS")
		)
		(fp_line
			(start 0.7874 0.4064)
			(end -0.7874 0.4064)
			(stroke
				(width 0.1524)
				(type default)
			)
			(layer "F.SilkS")
		)
		(fp_line
			(start -0.7874 0.4064)
			(end -0.7874 -0.4064)
			(stroke
				(width 0.1524)
				(type default)
			)
			(layer "F.SilkS")
		)
		(fp_line
			(start -0.12065 -0.305054)
			(end -0.12065 -0.2794)
			(stroke
				(width 0.1)
				(type default)
			)
			(layer "F.Fab")
		)
		(fp_line
			(start -0.67945 -0.305054)
			(end -0.12065 -0.305054)
			(stroke
				(width 0.1)
				(type default)
			)
			(layer "F.Fab")
		)
		(fp_line
			(start 0.67945 -0.3048)
			(end 0.67945 0.3048)
			(stroke
				(width 0.1)
				(type default)
			)
			(layer "F.Fab")
		)
		(fp_line
			(start 0.12065 -0.3048)
			(end 0.67945 -0.3048)
			(stroke
				(width 0.1)
				(type default)
			)
			(layer "F.Fab")
		)
		(fp_line
			(start 0.12065 -0.2794)
			(end 0.12065 -0.3048)
			(stroke
				(width 0.1)
				(type default)
			)
			(layer "F.Fab")
		)
		(fp_line
			(start -0.12065 -0.2794)
			(end 0.12065 -0.2794)
			(stroke
				(width 0.1)
				(type default)
			)
			(layer "F.Fab")
		)
		(fp_line
			(start 0.120396 0.2794)
			(end -0.12065 0.2794)
			(stroke
				(width 0.1)
				(type default)
			)
			(layer "F.Fab")
		)
		(fp_line
			(start -0.12065 0.2794)
			(end -0.12065 0.3048)
			(stroke
				(width 0.1)
				(type default)
			)
			(layer "F.Fab")
		)
		(fp_line
			(start 0.67945 0.3048)
			(end 0.120396 0.3048)
			(stroke
				(width 0.1)
				(type default)
			)
			(layer "F.Fab")
		)
		(fp_line
			(start 0.120396 0.3048)
			(end 0.120396 0.2794)
			(stroke
				(width 0.1)
				(type default)
			)
			(layer "F.Fab")
		)
		(fp_line
			(start -0.12065 0.3048)
			(end -0.67945 0.3048)
			(stroke
				(width 0.1)
				(type default)
			)
			(layer "F.Fab")
		)
		(fp_line
			(start -0.67945 0.3048)
			(end -0.67945 -0.305054)
			(stroke
				(width 0.1)
				(type default)
			)
			(layer "F.Fab")
		)
		(pad "1" smd circle
			(at -0.40005 0 90)
			(size 0 0)
			(layers "F.Cu" "F.Mask" "F.Paste")
			(net "GND")
		)
		(pad "2" smd circle
			(at 0.40005 0 90)
			(size 0 0)
			(layers "F.Cu" "F.Mask" "F.Paste")
			(net "PEX0_SPARE4")
		)
	)
	(footprint ""
		(layer "F.Cu")
		(at 341.546942 -37.47516)
		(property "Reference" "R6110"
			(at 0 0 0)
			(layer "F.SilkS")
			(hide yes)
			(effects
				(font
					(size 1.27 1.27)
				)
			)
		)
		(property "Value" ""
			(at 0 0 0)
			(layer "F.Fab")
			(effects
				(font
					(size 1.27 1.27)
				)
			)
		)
		(duplicate_pad_numbers_are_jumpers no)
		(fp_line
			(start -0.7874 -0.4064)
			(end 0.7874 -0.4064)
			(stroke
				(width 0.1524)
				(type default)
			)
			(layer "F.SilkS")
		)
		(fp_line
			(start -0.7874 0.4064)
			(end -0.7874 -0.4064)
			(stroke
				(width 0.1524)
				(type default)
			)
			(layer "F.SilkS")
		)
		(fp_line
			(start 0.7874 -0.4064)
			(end 0.7874 0.4064)
			(stroke
				(width 0.1524)
				(type default)
			)
			(layer "F.SilkS")
		)
		(fp_line
			(start 0.7874 0.4064)
			(end -0.7874 0.4064)
			(stroke
				(width 0.1524)
				(type default)
			)
			(layer "F.SilkS")
		)
		(fp_line
			(start -0.67945 -0.305054)
			(end -0.12065 -0.305054)
			(stroke
				(width 0.1)
				(type default)
			)
			(layer "F.Fab")
		)
		(fp_line
			(start -0.67945 0.3048)
			(end -0.67945 -0.305054)
			(stroke
				(width 0.1)
				(type default)
			)
			(layer "F.Fab")
		)
		(fp_line
			(start -0.12065 -0.305054)
			(end -0.12065 -0.2794)
			(stroke
				(width 0.1)
				(type default)
			)
			(layer "F.Fab")
		)
		(fp_line
			(start -0.12065 -0.2794)
			(end 0.12065 -0.2794)
			(stroke
				(width 0.1)
				(type default)
			)
			(layer "F.Fab")
		)
		(fp_line
			(start -0.12065 0.2794)
			(end -0.12065 0.3048)
			(stroke
				(width 0.1)
				(type default)
			)
			(layer "F.Fab")
		)
		(fp_line
			(start -0.12065 0.3048)
			(end -0.67945 0.3048)
			(stroke
				(width 0.1)
				(type default)
			)
			(layer "F.Fab")
		)
		(fp_line
			(start 0.120396 0.2794)
			(end -0.12065 0.2794)
			(stroke
				(width 0.1)
				(type default)
			)
			(layer "F.Fab")
		)
		(fp_line
			(start 0.120396 0.3048)
			(end 0.120396 0.2794)
			(stroke
				(width 0.1)
				(type default)
			)
			(layer "F.Fab")
		)
		(fp_line
			(start 0.12065 -0.3048)
			(end 0.67945 -0.3048)
			(stroke
				(width 0.1)
				(type default)
			)
			(layer "F.Fab")
		)
		(fp_line
			(start 0.12065 -0.2794)
			(end 0.12065 -0.3048)
			(stroke
				(width 0.1)
				(type default)
			)
			(layer "F.Fab")
		)
		(fp_line
			(start 0.67945 -0.3048)
			(end 0.67945 0.3048)
			(stroke
				(width 0.1)
				(type default)
			)
			(layer "F.Fab")
		)
		(fp_line
			(start 0.67945 0.3048)
			(end 0.120396 0.3048)
			(stroke
				(width 0.1)
				(type default)
			)
			(layer "F.Fab")
		)
		(pad "1" smd circle
			(at -0.40005 0)
			(size 0 0)
			(layers "F.Cu" "F.Mask" "F.Paste")
			(net "P3V3_SSD12")
		)
		(pad "2" smd circle
			(at 0.40005 0)
			(size 0 0)
			(layers "F.Cu" "F.Mask" "F.Paste")
			(net "P3V3_SSD12_PG_G1")
		)
	)
	(footprint ""
		(layer "F.Cu")
		(at 19.47164 -25.342342 -90)
		(property "Reference" "R409"
			(at 0 0 270)
			(layer "F.SilkS")
			(hide yes)
			(effects
				(font
					(size 1.27 1.27)
				)
			)
		)
		(property "Value" ""
			(at 0 0 270)
			(layer "F.Fab")
			(effects
				(font
					(size 1.27 1.27)
				)
			)
		)
		(duplicate_pad_numbers_are_jumpers no)
		(fp_line
			(start -0.7874 0.4064)
			(end -0.7874 -0.4064)
			(stroke
				(width 0.1524)
				(type default)
			)
			(layer "F.SilkS")
		)
		(fp_line
			(start 0.7874 0.4064)
			(end -0.7874 0.4064)
			(stroke
				(width 0.1524)
				(type default)
			)
			(layer "F.SilkS")
		)
		(fp_line
			(start -0.7874 -0.4064)
			(end 0.7874 -0.4064)
			(stroke
				(width 0.1524)
				(type default)
			)
			(layer "F.SilkS")
		)
		(fp_line
			(start 0.7874 -0.4064)
			(end 0.7874 0.4064)
			(stroke
				(width 0.1524)
				(type default)
			)
			(layer "F.SilkS")
		)
		(fp_line
			(start -0.67945 0.3048)
			(end -0.67945 -0.305054)
			(stroke
				(width 0.1)
				(type default)
			)
			(layer "F.Fab")
		)
		(fp_line
			(start -0.12065 0.3048)
			(end -0.67945 0.3048)
			(stroke
				(width 0.1)
				(type default)
			)
			(layer "F.Fab")
		)
		(fp_line
			(start 0.120396 0.3048)
			(end 0.120396 0.2794)
			(stroke
				(width 0.1)
				(type default)
			)
			(layer "F.Fab")
		)
		(fp_line
			(start 0.67945 0.3048)
			(end 0.120396 0.3048)
			(stroke
				(width 0.1)
				(type default)
			)
			(layer "F.Fab")
		)
		(fp_line
			(start -0.12065 0.2794)
			(end -0.12065 0.3048)
			(stroke
				(width 0.1)
				(type default)
			)
			(layer "F.Fab")
		)
		(fp_line
			(start 0.120396 0.2794)
			(end -0.12065 0.2794)
			(stroke
				(width 0.1)
				(type default)
			)
			(layer "F.Fab")
		)
		(fp_line
			(start -0.12065 -0.2794)
			(end 0.12065 -0.2794)
			(stroke
				(width 0.1)
				(type default)
			)
			(layer "F.Fab")
		)
		(fp_line
			(start 0.12065 -0.2794)
			(end 0.12065 -0.3048)
			(stroke
				(width 0.1)
				(type default)
			)
			(layer "F.Fab")
		)
		(fp_line
			(start 0.12065 -0.3048)
			(end 0.67945 -0.3048)
			(stroke
				(width 0.1)
				(type default)
			)
			(layer "F.Fab")
		)
		(fp_line
			(start 0.67945 -0.3048)
			(end 0.67945 0.3048)
			(stroke
				(width 0.1)
				(type default)
			)
			(layer "F.Fab")
		)
		(fp_line
			(start -0.67945 -0.305054)
			(end -0.12065 -0.305054)
			(stroke
				(width 0.1)
				(type default)
			)
			(layer "F.Fab")
		)
		(fp_line
			(start -0.12065 -0.305054)
			(end -0.12065 -0.2794)
			(stroke
				(width 0.1)
				(type default)
			)
			(layer "F.Fab")
		)
		(pad "1" smd circle
			(at -0.40005 0 270)
			(size 0 0)
			(layers "F.Cu" "F.Mask" "F.Paste")
			(net "P3V3_SSD0")
		)
		(pad "2" smd circle
			(at 0.40005 0 270)
			(size 0 0)
			(layers "F.Cu" "F.Mask" "F.Paste")
			(net "DUALPORT_N_SSD0")
		)
	)
	(footprint ""
		(layer "F.Cu")
		(at 17.006316 -306.28209)
		(property "Reference" "PJ9"
			(at 1.541018 -0.15875 0)
			(unlocked yes)
			(layer "F.SilkS")
			(effects
				(font
					(size 0.7874 0.5842)
					(thickness 0.1524)
				)
				(justify left)
			)
		)
		(property "Value" ""
			(at 0 0 0)
			(layer "F.Fab")
			(effects
				(font
					(size 1.27 1.27)
				)
			)
		)
		(duplicate_pad_numbers_are_jumpers no)
		(pad "1" smd circle
			(at -0.40005 0 90)
			(size 0 0)
			(layers "F.Cu" "F.Mask" "F.Paste")
			(net "SH_P1V25_PEX0_FB_P")
		)
		(pad "2" smd rect
			(at 0.40005 0 180)
			(size 0.4572 0.508)
			(layers "F.Cu" "F.Mask" "F.Paste")
			(net "P1V25_PEX0")
		)
		(zone
			(layer "F.Cu")
			(hatch none 0.5)
			(connect_pads
				(clearance 0)
			)
			(min_thickness 0.25)
			(keepout
				(tracks allowed)
				(vias not_allowed)
				(pads allowed)
				(copperpour not_allowed)
				(footprints allowed)
			)
			(placement
				(enabled no)
				(sheetname "")
			)
			(fill
				(thermal_gap 0.5)
				(thermal_bridge_width 0.5)
				(island_removal_mode 0)
			)
			(polygon
				(pts
					(xy 16.320516 -305.97729) (xy 17.692116 -305.97729) (xy 17.692116 -306.58689) (xy 16.320516 -306.58689)
				)
			)
		)
	)
)
